FILE_TYPE = CONNECTIVITY;
{Allegro Design Entry HDL 16.5-S008 (v16-5-13Y) 10/18/2011}
"PAGE_NUMBER" = 1;
0"NC";
1"G\I";
2"P12V_STBY \G";
%"SYNONYM"
"1","(1850,2050)","0","mstr_standard","4P";
;
NEEDS_NO_SIZE"TRUE"
BODY_TYPE"PLUMBING"
CDS_LIB"mstr_standard";
"A\NWC\NAC"1;
"A\NWC\NAC"2;
%"DRAWING"
"2","(1275,1750)","0","mstr_standard","";
;
LAST_MODIFIED"Tue Oct 25 13:21:17 2011"
TITLE"P12V_STBY"
ABBREV"P12V_STBY";
END.
